(kicad_pcb
	(version 20260206)
	(generator "pcbnew")
	(generator_version "10.0")
	(general
		(thickness 1.6)
		(legacy_teardrops no)
	)
	(paper "A4")
	(title_block
		(title "01162023_DA0F0TEBIF0_F0T_Expander_BD_F_brd_V02_OCP.brd")
		(comment 1 "Grand Teton / footprints 6123-6128 of 9728")
	)
	(layers
		(0 "F.Cu" signal "TOP")
		(4 "In1.Cu" signal "GND")
		(6 "In2.Cu" signal "VCC")
		(8 "In3.Cu" signal "VCC1")
		(10 "In4.Cu" signal "GND1")
		(12 "In5.Cu" signal "IN1")
		(14 "In6.Cu" signal "GND2")
		(16 "In7.Cu" signal "IN2")
		(18 "In8.Cu" signal "GND3")
		(20 "In9.Cu" signal "IN3")
		(22 "In10.Cu" signal "GND4")
		(24 "In11.Cu" signal "IN4")
		(26 "In12.Cu" signal "GND5")
		(28 "In13.Cu" signal "IN5")
		(30 "In14.Cu" signal "GND6")
		(32 "In15.Cu" signal "IN6")
		(34 "In16.Cu" signal "GND7")
		(2 "B.Cu" signal "BOTTOM")
		(9 "F.Adhes" user "F.Adhesive")
		(11 "B.Adhes" user "B.Adhesive")
		(13 "F.Paste" user "Package Geometry/Pastemask Top")
		(15 "B.Paste" user "Package Geometry/Pastemask Bottom")
		(5 "F.SilkS" user "Ref Des/Silkscreen Top")
		(7 "B.SilkS" user "Ref Des/Silkscreen Bottom")
		(1 "F.Mask" user "Board Geometry/Soldermask Top")
		(3 "B.Mask" user "Board Geometry/Soldermask Bottom")
		(17 "Dwgs.User" user "User.Drawings")
		(19 "Cmts.User" user "User.Comments")
		(21 "Eco1.User" user "User.Eco1")
		(23 "Eco2.User" user "User.Eco2")
		(25 "Edge.Cuts" user "Board Geometry/Outline")
		(27 "Margin" user)
		(31 "F.CrtYd" user "Package Geometry/Place Bound Top")
		(29 "B.CrtYd" user "Package Geometry/Place Bound Bottom")
		(35 "F.Fab" user "Ref Des/Assembly Top")
		(33 "B.Fab" user "Ref Des/Assembly Bottom")
	)
	(footprint ""
		(layer "F.Cu")
		(at 352.920554 -82.644234)
		(property "Reference" "R1627"
			(at 0 0 0)
			(layer "F.SilkS")
			(hide yes)
			(effects
				(font
					(size 1.27 1.27)
				)
			)
		)
		(property "Value" ""
			(at 0 0 0)
			(layer "F.Fab")
			(effects
				(font
					(size 1.27 1.27)
				)
			)
		)
		(duplicate_pad_numbers_are_jumpers no)
		(fp_line
			(start -0.7874 -0.4064)
			(end 0.7874 -0.4064)
			(stroke
				(width 0.1524)
				(type default)
			)
			(layer "F.SilkS")
		)
		(fp_line
			(start -0.7874 0.4064)
			(end -0.7874 -0.4064)
			(stroke
				(width 0.1524)
				(type default)
			)
			(layer "F.SilkS")
		)
		(fp_line
			(start 0.7874 -0.4064)
			(end 0.7874 0.4064)
			(stroke
				(width 0.1524)
				(type default)
			)
			(layer "F.SilkS")
		)
		(fp_line
			(start 0.7874 0.4064)
			(end -0.7874 0.4064)
			(stroke
				(width 0.1524)
				(type default)
			)
			(layer "F.SilkS")
		)
		(fp_line
			(start -0.67945 -0.305054)
			(end -0.12065 -0.305054)
			(stroke
				(width 0.1)
				(type default)
			)
			(layer "F.Fab")
		)
		(fp_line
			(start -0.67945 0.3048)
			(end -0.67945 -0.305054)
			(stroke
				(width 0.1)
				(type default)
			)
			(layer "F.Fab")
		)
		(fp_line
			(start -0.12065 -0.305054)
			(end -0.12065 -0.2794)
			(stroke
				(width 0.1)
				(type default)
			)
			(layer "F.Fab")
		)
		(fp_line
			(start -0.12065 -0.2794)
			(end 0.12065 -0.2794)
			(stroke
				(width 0.1)
				(type default)
			)
			(layer "F.Fab")
		)
		(fp_line
			(start -0.12065 0.2794)
			(end -0.12065 0.3048)
			(stroke
				(width 0.1)
				(type default)
			)
			(layer "F.Fab")
		)
		(fp_line
			(start -0.12065 0.3048)
			(end -0.67945 0.3048)
			(stroke
				(width 0.1)
				(type default)
			)
			(layer "F.Fab")
		)
		(fp_line
			(start 0.120396 0.2794)
			(end -0.12065 0.2794)
			(stroke
				(width 0.1)
				(type default)
			)
			(layer "F.Fab")
		)
		(fp_line
			(start 0.120396 0.3048)
			(end 0.120396 0.2794)
			(stroke
				(width 0.1)
				(type default)
			)
			(layer "F.Fab")
		)
		(fp_line
			(start 0.12065 -0.3048)
			(end 0.67945 -0.3048)
			(stroke
				(width 0.1)
				(type default)
			)
			(layer "F.Fab")
		)
		(fp_line
			(start 0.12065 -0.2794)
			(end 0.12065 -0.3048)
			(stroke
				(width 0.1)
				(type default)
			)
			(layer "F.Fab")
		)
		(fp_line
			(start 0.67945 -0.3048)
			(end 0.67945 0.3048)
			(stroke
				(width 0.1)
				(type default)
			)
			(layer "F.Fab")
		)
		(fp_line
			(start 0.67945 0.3048)
			(end 0.120396 0.3048)
			(stroke
				(width 0.1)
				(type default)
			)
			(layer "F.Fab")
		)
		(pad "1" smd circle
			(at -0.40005 0)
			(size 0 0)
			(layers "F.Cu" "F.Mask" "F.Paste")
			(net "SMB_BIC_I2C9_MUX1_SSD11_R_SDA")
		)
		(pad "2" smd circle
			(at 0.40005 0)
			(size 0 0)
			(layers "F.Cu" "F.Mask" "F.Paste")
			(net "SMB_BIC_I2C9_MUX1_SSD11_SDA")
		)
	)
	(footprint ""
		(layer "F.Cu")
		(at 14.261846 -208.993232 -90)
		(property "Reference" "C4414"
			(at 0 0 270)
			(layer "F.SilkS")
			(hide yes)
			(effects
				(font
					(size 1.27 1.27)
				)
			)
		)
		(property "Value" ""
			(at 0 0 270)
			(layer "F.Fab")
			(effects
				(font
					(size 1.27 1.27)
				)
			)
		)
		(duplicate_pad_numbers_are_jumpers no)
		(fp_line
			(start -0.7874 0.4064)
			(end -0.7874 -0.4064)
			(stroke
				(width 0.1524)
				(type default)
			)
			(layer "F.SilkS")
		)
		(fp_line
			(start 0.7874 0.4064)
			(end -0.7874 0.4064)
			(stroke
				(width 0.1524)
				(type default)
			)
			(layer "F.SilkS")
		)
		(fp_line
			(start -0.7874 -0.4064)
			(end 0.7874 -0.4064)
			(stroke
				(width 0.1524)
				(type default)
			)
			(layer "F.SilkS")
		)
		(fp_line
			(start 0.7874 -0.4064)
			(end 0.7874 0.4064)
			(stroke
				(width 0.1524)
				(type default)
			)
			(layer "F.SilkS")
		)
		(fp_line
			(start -0.67945 0.3048)
			(end -0.67945 -0.305054)
			(stroke
				(width 0.1)
				(type default)
			)
			(layer "F.Fab")
		)
		(fp_line
			(start -0.12065 0.3048)
			(end -0.67945 0.3048)
			(stroke
				(width 0.1)
				(type default)
			)
			(layer "F.Fab")
		)
		(fp_line
			(start 0.120396 0.3048)
			(end 0.120396 0.2794)
			(stroke
				(width 0.1)
				(type default)
			)
			(layer "F.Fab")
		)
		(fp_line
			(start 0.67945 0.3048)
			(end 0.120396 0.3048)
			(stroke
				(width 0.1)
				(type default)
			)
			(layer "F.Fab")
		)
		(fp_line
			(start -0.12065 0.2794)
			(end -0.12065 0.3048)
			(stroke
				(width 0.1)
				(type default)
			)
			(layer "F.Fab")
		)
		(fp_line
			(start 0.120396 0.2794)
			(end -0.12065 0.2794)
			(stroke
				(width 0.1)
				(type default)
			)
			(layer "F.Fab")
		)
		(fp_line
			(start -0.12065 -0.2794)
			(end 0.12065 -0.2794)
			(stroke
				(width 0.1)
				(type default)
			)
			(layer "F.Fab")
		)
		(fp_line
			(start 0.12065 -0.2794)
			(end 0.12065 -0.3048)
			(stroke
				(width 0.1)
				(type default)
			)
			(layer "F.Fab")
		)
		(fp_line
			(start 0.12065 -0.3048)
			(end 0.67945 -0.3048)
			(stroke
				(width 0.1)
				(type default)
			)
			(layer "F.Fab")
		)
		(fp_line
			(start 0.67945 -0.3048)
			(end 0.67945 0.3048)
			(stroke
				(width 0.1)
				(type default)
			)
			(layer "F.Fab")
		)
		(fp_line
			(start -0.67945 -0.305054)
			(end -0.12065 -0.305054)
			(stroke
				(width 0.1)
				(type default)
			)
			(layer "F.Fab")
		)
		(fp_line
			(start -0.12065 -0.305054)
			(end -0.12065 -0.2794)
			(stroke
				(width 0.1)
				(type default)
			)
			(layer "F.Fab")
		)
		(pad "1" smd circle
			(at -0.40005 0 270)
			(size 0 0)
			(layers "F.Cu" "F.Mask" "F.Paste")
			(net "P5V_AUX")
		)
		(pad "2" smd circle
			(at 0.40005 0 270)
			(size 0 0)
			(layers "F.Cu" "F.Mask" "F.Paste")
			(net "GND")
		)
	)
	(footprint ""
		(layer "F.Cu")
		(at 399.14322 -343.952322 90)
		(property "Reference" "C750"
			(at 0 0 90)
			(layer "F.SilkS")
			(hide yes)
			(effects
				(font
					(size 1.27 1.27)
				)
			)
		)
		(property "Value" ""
			(at 0 0 90)
			(layer "F.Fab")
			(effects
				(font
					(size 1.27 1.27)
				)
			)
		)
		(duplicate_pad_numbers_are_jumpers no)
		(fp_line
			(start 0.299974 -0.150114)
			(end 0.299974 0.150114)
			(stroke
				(width 0.1)
				(type default)
			)
			(layer "F.Fab")
		)
		(fp_line
			(start -0.299974 -0.150114)
			(end 0.299974 -0.150114)
			(stroke
				(width 0.1)
				(type default)
			)
			(layer "F.Fab")
		)
		(fp_line
			(start 0.299974 0.150114)
			(end -0.299974 0.150114)
			(stroke
				(width 0.1)
				(type default)
			)
			(layer "F.Fab")
		)
		(fp_line
			(start -0.299974 0.150114)
			(end -0.299974 -0.150114)
			(stroke
				(width 0.1)
				(type default)
			)
			(layer "F.Fab")
		)
		(pad "1" smd rect
			(at -0.2667 0 90)
			(size 0.3048 0.381)
			(layers "F.Cu" "F.Mask" "F.Paste")
			(net "P5E_PEX3_STN5_TX_DP<85>")
		)
		(pad "2" smd rect
			(at 0.2667 0 90)
			(size 0.3048 0.381)
			(layers "F.Cu" "F.Mask" "F.Paste")
			(net "P5E_PEX3_STN5_TX_C_DP<85>")
		)
	)
	(footprint ""
		(layer "F.Cu")
		(at 194.343782 -45.88891)
		(property "Reference" "R575"
			(at 0 0 0)
			(layer "F.SilkS")
			(hide yes)
			(effects
				(font
					(size 1.27 1.27)
				)
			)
		)
		(property "Value" ""
			(at 0 0 0)
			(layer "F.Fab")
			(effects
				(font
					(size 1.27 1.27)
				)
			)
		)
		(duplicate_pad_numbers_are_jumpers no)
		(fp_line
			(start -0.7874 -0.4064)
			(end 0.7874 -0.4064)
			(stroke
				(width 0.1524)
				(type default)
			)
			(layer "F.SilkS")
		)
		(fp_line
			(start -0.7874 0.4064)
			(end -0.7874 -0.4064)
			(stroke
				(width 0.1524)
				(type default)
			)
			(layer "F.SilkS")
		)
		(fp_line
			(start 0.7874 -0.4064)
			(end 0.7874 0.4064)
			(stroke
				(width 0.1524)
				(type default)
			)
			(layer "F.SilkS")
		)
		(fp_line
			(start 0.7874 0.4064)
			(end -0.7874 0.4064)
			(stroke
				(width 0.1524)
				(type default)
			)
			(layer "F.SilkS")
		)
		(fp_line
			(start -0.67945 -0.305054)
			(end -0.12065 -0.305054)
			(stroke
				(width 0.1)
				(type default)
			)
			(layer "F.Fab")
		)
		(fp_line
			(start -0.67945 0.3048)
			(end -0.67945 -0.305054)
			(stroke
				(width 0.1)
				(type default)
			)
			(layer "F.Fab")
		)
		(fp_line
			(start -0.12065 -0.305054)
			(end -0.12065 -0.2794)
			(stroke
				(width 0.1)
				(type default)
			)
			(layer "F.Fab")
		)
		(fp_line
			(start -0.12065 -0.2794)
			(end 0.12065 -0.2794)
			(stroke
				(width 0.1)
				(type default)
			)
			(layer "F.Fab")
		)
		(fp_line
			(start -0.12065 0.2794)
			(end -0.12065 0.3048)
			(stroke
				(width 0.1)
				(type default)
			)
			(layer "F.Fab")
		)
		(fp_line
			(start -0.12065 0.3048)
			(end -0.67945 0.3048)
			(stroke
				(width 0.1)
				(type default)
			)
			(layer "F.Fab")
		)
		(fp_line
			(start 0.120396 0.2794)
			(end -0.12065 0.2794)
			(stroke
				(width 0.1)
				(type default)
			)
			(layer "F.Fab")
		)
		(fp_line
			(start 0.120396 0.3048)
			(end 0.120396 0.2794)
			(stroke
				(width 0.1)
				(type default)
			)
			(layer "F.Fab")
		)
		(fp_line
			(start 0.12065 -0.3048)
			(end 0.67945 -0.3048)
			(stroke
				(width 0.1)
				(type default)
			)
			(layer "F.Fab")
		)
		(fp_line
			(start 0.12065 -0.2794)
			(end 0.12065 -0.3048)
			(stroke
				(width 0.1)
				(type default)
			)
			(layer "F.Fab")
		)
		(fp_line
			(start 0.67945 -0.3048)
			(end 0.67945 0.3048)
			(stroke
				(width 0.1)
				(type default)
			)
			(layer "F.Fab")
		)
		(fp_line
			(start 0.67945 0.3048)
			(end 0.120396 0.3048)
			(stroke
				(width 0.1)
				(type default)
			)
			(layer "F.Fab")
		)
		(pad "1" smd circle
			(at -0.40005 0)
			(size 0 0)
			(layers "F.Cu" "F.Mask" "F.Paste")
			(net "SSD6_ADC_A0")
		)
		(pad "2" smd circle
			(at 0.40005 0)
			(size 0 0)
			(layers "F.Cu" "F.Mask" "F.Paste")
			(net "GND")
		)
	)
	(footprint ""
		(layer "F.Cu")
		(at 461.33004 -258.331208 -90)
		(property "Reference" "R6564"
			(at 0 0 270)
			(layer "F.SilkS")
			(hide yes)
			(effects
				(font
					(size 1.27 1.27)
				)
			)
		)
		(property "Value" ""
			(at 0 0 270)
			(layer "F.Fab")
			(effects
				(font
					(size 1.27 1.27)
				)
			)
		)
		(duplicate_pad_numbers_are_jumpers no)
		(fp_line
			(start -0.7874 0.4064)
			(end -0.7874 -0.4064)
			(stroke
				(width 0.1524)
				(type default)
			)
			(layer "F.SilkS")
		)
		(fp_line
			(start 0.7874 0.4064)
			(end -0.7874 0.4064)
			(stroke
				(width 0.1524)
				(type default)
			)
			(layer "F.SilkS")
		)
		(fp_line
			(start -0.7874 -0.4064)
			(end 0.7874 -0.4064)
			(stroke
				(width 0.1524)
				(type default)
			)
			(layer "F.SilkS")
		)
		(fp_line
			(start 0.7874 -0.4064)
			(end 0.7874 0.4064)
			(stroke
				(width 0.1524)
				(type default)
			)
			(layer "F.SilkS")
		)
		(fp_line
			(start -0.67945 0.3048)
			(end -0.67945 -0.305054)
			(stroke
				(width 0.1)
				(type default)
			)
			(layer "F.Fab")
		)
		(fp_line
			(start -0.12065 0.3048)
			(end -0.67945 0.3048)
			(stroke
				(width 0.1)
				(type default)
			)
			(layer "F.Fab")
		)
		(fp_line
			(start 0.120396 0.3048)
			(end 0.120396 0.2794)
			(stroke
				(width 0.1)
				(type default)
			)
			(layer "F.Fab")
		)
		(fp_line
			(start 0.67945 0.3048)
			(end 0.120396 0.3048)
			(stroke
				(width 0.1)
				(type default)
			)
			(layer "F.Fab")
		)
		(fp_line
			(start -0.12065 0.2794)
			(end -0.12065 0.3048)
			(stroke
				(width 0.1)
				(type default)
			)
			(layer "F.Fab")
		)
		(fp_line
			(start 0.120396 0.2794)
			(end -0.12065 0.2794)
			(stroke
				(width 0.1)
				(type default)
			)
			(layer "F.Fab")
		)
		(fp_line
			(start -0.12065 -0.2794)
			(end 0.12065 -0.2794)
			(stroke
				(width 0.1)
				(type default)
			)
			(layer "F.Fab")
		)
		(fp_line
			(start 0.12065 -0.2794)
			(end 0.12065 -0.3048)
			(stroke
				(width 0.1)
				(type default)
			)
			(layer "F.Fab")
		)
		(fp_line
			(start 0.12065 -0.3048)
			(end 0.67945 -0.3048)
			(stroke
				(width 0.1)
				(type default)
			)
			(layer "F.Fab")
		)
		(fp_line
			(start 0.67945 -0.3048)
			(end 0.67945 0.3048)
			(stroke
				(width 0.1)
				(type default)
			)
			(layer "F.Fab")
		)
		(fp_line
			(start -0.67945 -0.305054)
			(end -0.12065 -0.305054)
			(stroke
				(width 0.1)
				(type default)
			)
			(layer "F.Fab")
		)
		(fp_line
			(start -0.12065 -0.305054)
			(end -0.12065 -0.2794)
			(stroke
				(width 0.1)
				(type default)
			)
			(layer "F.Fab")
		)
		(pad "1" smd circle
			(at -0.40005 0 270)
			(size 0 0)
			(layers "F.Cu" "F.Mask" "F.Paste")
			(net "P1V25_SERDES_VDDPLL_PEX3")
		)
		(pad "2" smd circle
			(at 0.40005 0 270)
			(size 0 0)
			(layers "F.Cu" "F.Mask" "F.Paste")
			(net "P1V25_SERDES_VDDPLL_PEX3_C11")
		)
	)
	(footprint ""
		(layer "F.Cu")
		(at 245.280434 -250.759722 -90)
		(property "Reference" "R6219"
			(at 0 0 270)
			(layer "F.SilkS")
			(hide yes)
			(effects
				(font
					(size 1.27 1.27)
				)
			)
		)
		(property "Value" ""
			(at 0 0 270)
			(layer "F.Fab")
			(effects
				(font
					(size 1.27 1.27)
				)
			)
		)
		(duplicate_pad_numbers_are_jumpers no)
		(fp_line
			(start -0.7874 0.4064)
			(end -0.7874 -0.4064)
			(stroke
				(width 0.1524)
				(type default)
			)
			(layer "F.SilkS")
		)
		(fp_line
			(start 0.7874 0.4064)
			(end -0.7874 0.4064)
			(stroke
				(width 0.1524)
				(type default)
			)
			(layer "F.SilkS")
		)
		(fp_line
			(start -0.7874 -0.4064)
			(end 0.7874 -0.4064)
			(stroke
				(width 0.1524)
				(type default)
			)
			(layer "F.SilkS")
		)
		(fp_line
			(start 0.7874 -0.4064)
			(end 0.7874 0.4064)
			(stroke
				(width 0.1524)
				(type default)
			)
			(layer "F.SilkS")
		)
		(fp_line
			(start -0.67945 0.3048)
			(end -0.67945 -0.305054)
			(stroke
				(width 0.1)
				(type default)
			)
			(layer "F.Fab")
		)
		(fp_line
			(start -0.12065 0.3048)
			(end -0.67945 0.3048)
			(stroke
				(width 0.1)
				(type default)
			)
			(layer "F.Fab")
		)
		(fp_line
			(start 0.120396 0.3048)
			(end 0.120396 0.2794)
			(stroke
				(width 0.1)
				(type default)
			)
			(layer "F.Fab")
		)
		(fp_line
			(start 0.67945 0.3048)
			(end 0.120396 0.3048)
			(stroke
				(width 0.1)
				(type default)
			)
			(layer "F.Fab")
		)
		(fp_line
			(start -0.12065 0.2794)
			(end -0.12065 0.3048)
			(stroke
				(width 0.1)
				(type default)
			)
			(layer "F.Fab")
		)
		(fp_line
			(start 0.120396 0.2794)
			(end -0.12065 0.2794)
			(stroke
				(width 0.1)
				(type default)
			)
			(layer "F.Fab")
		)
		(fp_line
			(start -0.12065 -0.2794)
			(end 0.12065 -0.2794)
			(stroke
				(width 0.1)
				(type default)
			)
			(layer "F.Fab")
		)
		(fp_line
			(start 0.12065 -0.2794)
			(end 0.12065 -0.3048)
			(stroke
				(width 0.1)
				(type default)
			)
			(layer "F.Fab")
		)
		(fp_line
			(start 0.12065 -0.3048)
			(end 0.67945 -0.3048)
			(stroke
				(width 0.1)
				(type default)
			)
			(layer "F.Fab")
		)
		(fp_line
			(start 0.67945 -0.3048)
			(end 0.67945 0.3048)
			(stroke
				(width 0.1)
				(type default)
			)
			(layer "F.Fab")
		)
		(fp_line
			(start -0.67945 -0.305054)
			(end -0.12065 -0.305054)
			(stroke
				(width 0.1)
				(type default)
			)
			(layer "F.Fab")
		)
		(fp_line
			(start -0.12065 -0.305054)
			(end -0.12065 -0.2794)
			(stroke
				(width 0.1)
				(type default)
			)
			(layer "F.Fab")
		)
		(pad "1" smd circle
			(at -0.40005 0 270)
			(size 0 0)
			(layers "F.Cu" "F.Mask" "F.Paste")
			(net "P3V3_AUX")
		)
		(pad "2" smd circle
			(at 0.40005 0 270)
			(size 0 0)
			(layers "F.Cu" "F.Mask" "F.Paste")
			(net "IRQ_BIC_RECOVER_IOEXP_N")
		)
	)
)
